(kicad_pcb
	(version 20221018)
	(generator pcbnew)
	(general
    (thickness 1.62)
  )
	(paper "A4")
	(title_block
    (title "ECP5 - Datacenter Secure Control Module (DC-SCM)")
    (date "2024-07-01")
    (rev "1.2.1")
		(comment 9 "footprints 164-171 of 506")
	)
	(layers
    (0 "F.Cu" signal)
    (1 "In1.Cu" power)
    (2 "In2.Cu" signal)
    (3 "In3.Cu" power)
    (4 "In4.Cu" power)
    (5 "In5.Cu" signal)
    (6 "In6.Cu" power)
    (31 "B.Cu" signal)
    (32 "B.Adhes" user "B.Adhesive")
    (33 "F.Adhes" user "F.Adhesive")
    (34 "B.Paste" user)
    (35 "F.Paste" user)
    (36 "B.SilkS" user "B.Silkscreen")
    (37 "F.SilkS" user "F.Silkscreen")
    (38 "B.Mask" user)
    (39 "F.Mask" user)
    (40 "Dwgs.User" user "User.Drawings")
    (41 "Cmts.User" user "User.Comments")
    (42 "Eco1.User" user "User.Eco1")
    (43 "Eco2.User" user "User.Eco2")
    (44 "Edge.Cuts" user)
    (45 "Margin" user)
    (46 "B.CrtYd" user "B.Courtyard")
    (47 "F.CrtYd" user "F.Courtyard")
    (48 "B.Fab" user)
    (49 "F.Fab" user)
  )
	(footprint "antmicro-footprints:C_0402_1005Metric" (layer "F.Cu")
    (at 93.15 61.735 -90)
    (descr "Capacitor SMD 0402")
    (tags "capacitor SMD 0402")
    (property "Author" "Antmicro")
    (property "Dielectric" "X5R")
    (property "License" "Apache-2.0")
    (property "MPN" "GRM155R61H104KE14D")
    (property "Manufacturer" "Murata")
    (property "Public" "False")
    (property "Sheetfile" "power-supply.kicad_sch")
    (property "Sheetname" "Power supply")
    (property "Val" "100n")
    (property "Voltage" "50V")
    (property "ki_description" "SMD Multilayer Ceramic Capacitor, 0.1 µF, 50 V, 0402 [1005 Metric], ± 10%, X5R, GRM Series")
    (property "ki_keywords" "0402, SMT, CAPACITOR, PASSIVE, CERAMIC, MLCC")
    (attr smd)
    (fp_text reference "C100" (at -0.48 -1.94 -90) (layer "F.SilkS")
        (effects (font (size 0.7 0.7) (thickness 0.127)))
    )
    (fp_text value "C_100n_0402" (at 0 1.17 90) (layer "F.Fab")
        (effects (font (size 1 1) (thickness 0.15)))
    )
    (fp_text user "${REFERENCE}" (at 0 0 90) (layer "F.Fab")
        (effects (font (size 0.25 0.25) (thickness 0.04)))
    )
    (fp_text user "Author: Antmicro" (at -0.939 3.399 -90) (layer "F.Fab") hide
        (effects (font (size 0.7 0.7) (thickness 0.15)) (justify left bottom))
    )
    (fp_text user "License: Apache-2.0" (at -0.939 5.799 -90) (layer "F.Fab") hide
        (effects (font (size 0.7 0.7) (thickness 0.15)) (justify left bottom))
    )
    (fp_rect (start -0.925 -0.47) (end 0.925 0.47)
      (stroke (width 0.05) (type default)) (fill none) (layer "F.CrtYd"))
    (fp_line (start -0.494 -0.25) (end 0.504 -0.25)
      (stroke (width 0.15) (type solid)) (layer "F.Fab"))
    (fp_line (start -0.494 0.248) (end -0.494 -0.25)
      (stroke (width 0.15) (type solid)) (layer "F.Fab"))
    (fp_line (start 0.504 -0.25) (end 0.504 0.248)
      (stroke (width 0.15) (type solid)) (layer "F.Fab"))
    (fp_line (start 0.504 0.248) (end -0.494 0.248)
      (stroke (width 0.15) (type solid)) (layer "F.Fab"))
    (pad "1" smd roundrect (at -0.48 0 270) (size 0.59 0.64) (layers "F.Cu" "F.Paste" "F.Mask") (roundrect_rratio 0.25)
      (net 1 "GND") (pintype "passive"))
    (pad "2" smd roundrect (at 0.48 0 270) (size 0.59 0.64) (layers "F.Cu" "F.Paste" "F.Mask") (roundrect_rratio 0.25)
      (net 232 "Net-(U13-AVIN)") (pintype "passive"))
  )
	(footprint "antmicro-footprints:R_0603_1608Metric" (layer "F.Cu")
    (at 91.95 61.55 -90)
    (descr "Resistor SMD 0603")
    (tags "resistor SMD 0603")
    (property "Author" "Antmicro")
    (property "License" "Apache-2.0")
    (property "MPN" "CR0603-FX-10R0ELF")
    (property "Manufacturer" "Bourns")
    (property "Public" "False")
    (property "Sheetfile" "power-supply.kicad_sch")
    (property "Sheetname" "Power supply")
    (property "Tolerance" "1%")
    (property "Val" "10R")
    (property "ki_description" "SMD Chip Resistor, 10 ohm, ± 1%, 100 mW, 0603 [1608 Metric], Thick Film, General Purpose")
    (property "ki_keywords" "0603, SMT, RESISTOR, PASSIVE")
    (attr smd)
    (fp_text reference "R88" (at 1.995 -3.2 -90) (layer "F.SilkS")
        (effects (font (size 0.7 0.7) (thickness 0.127)))
    )
    (fp_text value "R_10R_0603" (at 0 1.9 90) (layer "F.Fab")
        (effects (font (size 1 1) (thickness 0.15)))
    )
    (fp_text user "License: Apache-2.0" (at -1.25 5.9 -90) (layer "F.Fab") hide
        (effects (font (size 0.7 0.7) (thickness 0.15)) (justify left bottom))
    )
    (fp_text user "${REFERENCE}" (at -1.25 3.898 -90) (layer "F.Fab") hide
        (effects (font (size 0.7 0.7) (thickness 0.15)) (justify left bottom))
    )
    (fp_text user "Author: Antmicro" (at -1.25 4.9 -90) (layer "F.Fab") hide
        (effects (font (size 0.7 0.7) (thickness 0.15)) (justify left bottom))
    )
    (fp_line (start -0.15 -0.4) (end 0.15 -0.4)
      (stroke (width 0.15) (type solid)) (layer "F.SilkS"))
    (fp_line (start -0.15 0.4) (end 0.15 0.4)
      (stroke (width 0.15) (type solid)) (layer "F.SilkS"))
    (fp_rect (start -1.25 -0.65) (end 1.25 0.65)
      (stroke (width 0.05) (type solid)) (fill none) (layer "F.CrtYd"))
    (fp_rect (start -0.8 -0.4) (end 0.8 0.4)
      (stroke (width 0.15) (type solid)) (fill none) (layer "F.Fab"))
    (pad "1" smd roundrect (at -0.7 0 270) (size 0.8 1) (layers "F.Cu" "F.Paste" "F.Mask") (roundrect_rratio 0.2)
      (net 11 "VCC5V0") (pintype "passive"))
    (pad "2" smd roundrect (at 0.7 0 270) (size 0.8 1) (layers "F.Cu" "F.Paste" "F.Mask") (roundrect_rratio 0.2)
      (net 232 "Net-(U13-AVIN)") (pintype "passive"))
  )
	(footprint "antmicro-footprints:C_0805_2012Metric" (layer "F.Cu")
    (at 89.31 62.295)
    (descr "Capacitor SMD 0805")
    (tags "capacitor SMD 0805")
    (property "Author" "Antmicro")
    (property "Dielectric" "")
    (property "License" "Apache-2.0")
    (property "MPN" "160R15X106KV4E")
    (property "Manufacturer" "Johanson Technology")
    (property "Public" "False")
    (property "Sheetfile" "power-supply.kicad_sch")
    (property "Sheetname" "Power supply")
    (property "Val" "10u")
    (property "Voltage" "")
    (property "ki_description" "SMD Multilayer Ceramic Capacitor, TANCERAM®, 10 µF, 16 V, 0805 [2012 Metric], ± 10%, X5R")
    (property "ki_keywords" "0805, SMT, CAPACITOR, PASSIVE")
    (attr smd)
    (fp_text reference "C96" (at 2.94 0.985 180) (layer "F.SilkS")
        (effects (font (size 0.7 0.7) (thickness 0.127)))
    )
    (fp_text value "C_10u_0805" (at 0 1.95) (layer "F.Fab")
        (effects (font (size 1 1) (thickness 0.15)))
    )
    (fp_text user "Author: Antmicro" (at -1.9 5.947) (layer "F.Fab") hide
        (effects (font (size 0.7 0.7) (thickness 0.15)) (justify left bottom))
    )
    (fp_text user "${REFERENCE}" (at -1.9 3.947) (layer "F.Fab") hide
        (effects (font (size 0.7 0.7) (thickness 0.15)) (justify left bottom))
    )
    (fp_text user "License: Apache-2.0" (at -1.9 4.947) (layer "F.Fab") hide
        (effects (font (size 0.7 0.7) (thickness 0.15)) (justify left bottom))
    )
    (fp_line (start -0.3 -0.7) (end 0.3 -0.7)
      (stroke (width 0.15) (type solid)) (layer "F.SilkS"))
    (fp_line (start -0.3 0.7) (end 0.3 0.7)
      (stroke (width 0.15) (type solid)) (layer "F.SilkS"))
    (fp_rect (start 1.95 -0.9) (end -1.95 0.9)
      (stroke (width 0.05) (type default)) (fill none) (layer "F.CrtYd"))
    (fp_rect (start -0.95 -0.675) (end 0.95 0.675)
      (stroke (width 0.15) (type solid)) (fill none) (layer "F.Fab"))
    (pad "1" smd roundrect (at -1.1 0) (size 1.2 1.3) (layers "F.Cu" "F.Paste" "F.Mask") (roundrect_rratio 0.25)
      (net 1 "GND") (pintype "passive"))
    (pad "2" smd roundrect (at 1.1 0) (size 1.2 1.3) (layers "F.Cu" "F.Paste" "F.Mask") (roundrect_rratio 0.25)
      (net 11 "VCC5V0") (pintype "passive"))
  )
	(footprint "antmicro-footprints:C_0805_2012Metric" (layer "F.Cu")
    (at 89.31 60.245)
    (descr "Capacitor SMD 0805")
    (tags "capacitor SMD 0805")
    (property "Author" "Antmicro")
    (property "Dielectric" "")
    (property "License" "Apache-2.0")
    (property "MPN" "160R15X106KV4E")
    (property "Manufacturer" "Johanson Technology")
    (property "Public" "False")
    (property "Sheetfile" "power-supply.kicad_sch")
    (property "Sheetname" "Power supply")
    (property "Val" "10u")
    (property "Voltage" "")
    (property "ki_description" "SMD Multilayer Ceramic Capacitor, TANCERAM®, 10 µF, 16 V, 0805 [2012 Metric], ± 10%, X5R")
    (property "ki_keywords" "0805, SMT, CAPACITOR, PASSIVE")
    (attr smd)
    (fp_text reference "C97" (at 2.72 -0.695 180) (layer "F.SilkS")
        (effects (font (size 0.7 0.7) (thickness 0.127)))
    )
    (fp_text value "C_10u_0805" (at 0 1.95) (layer "F.Fab")
        (effects (font (size 1 1) (thickness 0.15)))
    )
    (fp_text user "License: Apache-2.0" (at -1.9 4.947) (layer "F.Fab") hide
        (effects (font (size 0.7 0.7) (thickness 0.15)) (justify left bottom))
    )
    (fp_text user "${REFERENCE}" (at -1.9 3.947) (layer "F.Fab") hide
        (effects (font (size 0.7 0.7) (thickness 0.15)) (justify left bottom))
    )
    (fp_text user "Author: Antmicro" (at -1.9 5.947) (layer "F.Fab") hide
        (effects (font (size 0.7 0.7) (thickness 0.15)) (justify left bottom))
    )
    (fp_line (start -0.3 -0.7) (end 0.3 -0.7)
      (stroke (width 0.15) (type solid)) (layer "F.SilkS"))
    (fp_line (start -0.3 0.7) (end 0.3 0.7)
      (stroke (width 0.15) (type solid)) (layer "F.SilkS"))
    (fp_rect (start 1.95 -0.9) (end -1.95 0.9)
      (stroke (width 0.05) (type default)) (fill none) (layer "F.CrtYd"))
    (fp_rect (start -0.95 -0.675) (end 0.95 0.675)
      (stroke (width 0.15) (type solid)) (fill none) (layer "F.Fab"))
    (pad "1" smd roundrect (at -1.1 0) (size 1.2 1.3) (layers "F.Cu" "F.Paste" "F.Mask") (roundrect_rratio 0.25)
      (net 1 "GND") (pintype "passive"))
    (pad "2" smd roundrect (at 1.1 0) (size 1.2 1.3) (layers "F.Cu" "F.Paste" "F.Mask") (roundrect_rratio 0.25)
      (net 11 "VCC5V0") (pintype "passive"))
  )
	(footprint "antmicro-footprints:C_0402_1005Metric" (layer "F.Cu")
    (at 87.4 143.05 -90)
    (descr "Capacitor SMD 0402")
    (tags "capacitor SMD 0402")
    (property "Author" "Antmicro")
    (property "Dielectric" "X5R")
    (property "License" "Apache-2.0")
    (property "MPN" "GRM155R61H104KE14D")
    (property "Manufacturer" "Murata")
    (property "Public" "False")
    (property "Sheetfile" "interfaces.kicad_sch")
    (property "Sheetname" "Interfaces")
    (property "Val" "100n")
    (property "Voltage" "50V")
    (property "ki_description" "SMD Multilayer Ceramic Capacitor, 0.1 µF, 50 V, 0402 [1005 Metric], ± 10%, X5R, GRM Series")
    (property "ki_keywords" "0402, SMT, CAPACITOR, PASSIVE, CERAMIC, MLCC")
    (attr smd)
    (fp_text reference "C248" (at -2.31 -0.1 90) (layer "F.SilkS")
        (effects (font (size 0.7 0.7) (thickness 0.127)))
    )
    (fp_text value "C_100n_0402" (at 0 1.17 90) (layer "F.Fab")
        (effects (font (size 1 1) (thickness 0.15)))
    )
    (fp_text user "License: Apache-2.0" (at -0.939 5.799 -90) (layer "F.Fab") hide
        (effects (font (size 0.7 0.7) (thickness 0.15)) (justify left bottom))
    )
    (fp_text user "Author: Antmicro" (at -0.939 3.399 -90) (layer "F.Fab") hide
        (effects (font (size 0.7 0.7) (thickness 0.15)) (justify left bottom))
    )
    (fp_text user "${REFERENCE}" (at 0 0 90) (layer "F.Fab")
        (effects (font (size 0.25 0.25) (thickness 0.04)))
    )
    (fp_rect (start -0.925 -0.47) (end 0.925 0.47)
      (stroke (width 0.05) (type default)) (fill none) (layer "F.CrtYd"))
    (fp_line (start -0.494 -0.25) (end 0.504 -0.25)
      (stroke (width 0.15) (type solid)) (layer "F.Fab"))
    (fp_line (start -0.494 0.248) (end -0.494 -0.25)
      (stroke (width 0.15) (type solid)) (layer "F.Fab"))
    (fp_line (start 0.504 -0.25) (end 0.504 0.248)
      (stroke (width 0.15) (type solid)) (layer "F.Fab"))
    (fp_line (start 0.504 0.248) (end -0.494 0.248)
      (stroke (width 0.15) (type solid)) (layer "F.Fab"))
    (pad "1" smd roundrect (at -0.48 0 270) (size 0.59 0.64) (layers "F.Cu" "F.Paste" "F.Mask") (roundrect_rratio 0.25)
      (net 1 "GND") (pintype "passive"))
    (pad "2" smd roundrect (at 0.48 0 270) (size 0.59 0.64) (layers "F.Cu" "F.Paste" "F.Mask") (roundrect_rratio 0.25)
      (net 12 "VCC1V0") (pintype "passive"))
  )
	(footprint "antmicro-footprints:SW_B3U-1000P_SMD" (layer "F.Cu")
    (at 71.65 94.75)
    (property "Author" "Antmicro")
    (property "License" "Apache-2.0")
    (property "MPN" "B3U-1000P")
    (property "Manufacturer" "Omron")
    (property "Sheetfile" "fpga-banks.kicad_sch")
    (property "Sheetname" "FPGA banks")
    (property "ki_description" "Tactile Switch, B3U, Top Actuated, Surface Mount, Round Button, 153 gf, 50mA at 12VDC")
    (property "ki_keywords" "VERTICAL, SMT, SWITCH, MECHANICAL, TACTILE")
    (attr smd)
    (fp_text reference "SW1" (at -3.125 1.3) (layer "F.SilkS")
        (effects (font (size 0.7 0.7) (thickness 0.127)))
    )
    (fp_text value "SW_B3U-1000P_SMD" (at 0 2.63) (layer "F.Fab")
        (effects (font (size 1 1) (thickness 0.15)))
    )
    (fp_text user "Author: Antmicro" (at -2.249 5.7) (layer "F.Fab") hide
        (effects (font (size 0.7 0.7) (thickness 0.15)) (justify left bottom))
    )
    (fp_text user "${REFERENCE}" (at 0 0) (layer "F.Fab")
        (effects (font (size 0.5 0.5) (thickness 0.05)))
    )
    (fp_text user "License: Apache-2.0" (at -2.249 6.9) (layer "F.Fab") hide
        (effects (font (size 0.7 0.7) (thickness 0.15)) (justify left bottom))
    )
    (fp_line (start -1.601 -0.95) (end -2 -0.95)
      (stroke (width 0.15) (type solid)) (layer "F.SilkS"))
    (fp_line (start -1.6 -1.4) (end -1.601 -0.95)
      (stroke (width 0.15) (type solid)) (layer "F.SilkS"))
    (fp_line (start -1.6 -1.4) (end -1.1 -1.4)
      (stroke (width 0.15) (type solid)) (layer "F.SilkS"))
    (fp_line (start -1.6 1.4) (end -1.6 0.95)
      (stroke (width 0.15) (type solid)) (layer "F.SilkS"))
    (fp_line (start -1.6 1.4) (end -1.1 1.4)
      (stroke (width 0.15) (type solid)) (layer "F.SilkS"))
    (fp_line (start 1.6 -1.4) (end 1.1 -1.4)
      (stroke (width 0.15) (type solid)) (layer "F.SilkS"))
    (fp_line (start 1.6 -1.4) (end 1.6 -0.95)
      (stroke (width 0.15) (type solid)) (layer "F.SilkS"))
    (fp_line (start 1.6 1.4) (end 1.1 1.4)
      (stroke (width 0.15) (type solid)) (layer "F.SilkS"))
    (fp_line (start 1.6 1.4) (end 1.6 0.95)
      (stroke (width 0.15) (type solid)) (layer "F.SilkS"))
    (fp_rect (start -2.249 -1.55) (end 2.25 1.549)
      (stroke (width 0.05) (type solid)) (fill none) (layer "F.CrtYd"))
    (fp_rect (start -1.5 -1.29) (end 1.499 1.289)
      (stroke (width 0.15) (type solid)) (fill none) (layer "F.Fab"))
    (pad "1" smd rect (at -1.7 0) (size 0.8 1.7) (layers "F.Cu" "F.Paste" "F.Mask")
      (net 268 "PROGRAM_N") (pinfunction "1") (pintype "passive"))
    (pad "2" smd rect (at 1.699 0) (size 0.8 1.7) (layers "F.Cu" "F.Paste" "F.Mask")
      (net 1 "GND") (pinfunction "2") (pintype "passive"))
  )
	(footprint "antmicro-footprints:R_0402_1005Metric" (layer "F.Cu")
    (at 78.24 73.64 -90)
    (descr "Resistor SMD 0402")
    (tags "resistor SMD 0402")
    (property "Author" "Antmicro")
    (property "License" "Apache-2.0")
    (property "MPN" "CR0402-FX-1003GLF")
    (property "Manufacturer" "Bourns")
    (property "Public" "False")
    (property "Sheetfile" "power-supply.kicad_sch")
    (property "Sheetname" "Power supply")
    (property "Tolerance" "1%")
    (property "Val" "100k")
    (property "ki_description" "SMD Chip Resistor, 100 kohm, ± 1%, 62.5 mW, 0402 [1005 Metric], Thick Film, General Purpose")
    (property "ki_keywords" "0402, SMT, RESISTOR, PASSIVE")
    (attr smd)
    (fp_text reference "R86" (at -2.45 4.9 -90) (layer "F.SilkS")
        (effects (font (size 0.7 0.7) (thickness 0.127)))
    )
    (fp_text value "R_100k_0402" (at 0 1.17 -90) (layer "F.Fab")
        (effects (font (size 1 1) (thickness 0.15)))
    )
    (fp_text user "License: Apache-2.0" (at -0.95 5.169 -90) (layer "F.Fab") hide
        (effects (font (size 0.7 0.7) (thickness 0.15)) (justify left bottom))
    )
    (fp_text user "Author: Antmicro" (at -0.95 4.169 -90) (layer "F.Fab") hide
        (effects (font (size 0.7 0.7) (thickness 0.15)) (justify left bottom))
    )
    (fp_text user "${REFERENCE}" (at 0 0 -90) (layer "F.Fab")
        (effects (font (size 0.25 0.25) (thickness 0.04)))
    )
    (fp_rect (start -0.925 -0.47) (end 0.925 0.47)
      (stroke (width 0.05) (type default)) (fill none) (layer "F.CrtYd"))
    (fp_rect (start -0.5 -0.25) (end 0.5 0.25)
      (stroke (width 0.15) (type solid)) (fill none) (layer "F.Fab"))
    (pad "1" smd roundrect (at -0.48 0 270) (size 0.59 0.64) (layers "F.Cu" "F.Paste" "F.Mask") (roundrect_rratio 0.25)
      (net 11 "VCC5V0") (pintype "passive"))
    (pad "2" smd roundrect (at 0.48 0 270) (size 0.59 0.64) (layers "F.Cu" "F.Paste" "F.Mask") (roundrect_rratio 0.25)
      (net 420 "Net-(U12-FLAG2)") (pintype "passive"))
  )
	(footprint "antmicro-footprints:R_0402_1005Metric" (layer "F.Cu")
    (at 77.24 73.64 -90)
    (descr "Resistor SMD 0402")
    (tags "resistor SMD 0402")
    (property "Author" "Antmicro")
    (property "License" "Apache-2.0")
    (property "MPN" "CR0402-FX-1003GLF")
    (property "Manufacturer" "Bourns")
    (property "Public" "False")
    (property "Sheetfile" "power-supply.kicad_sch")
    (property "Sheetname" "Power supply")
    (property "Tolerance" "1%")
    (property "Val" "100k")
    (property "ki_description" "SMD Chip Resistor, 100 kohm, ± 1%, 62.5 mW, 0402 [1005 Metric], Thick Film, General Purpose")
    (property "ki_keywords" "0402, SMT, RESISTOR, PASSIVE")
    (attr smd)
    (fp_text reference "R87" (at -2.45 4.9 -90) (layer "F.SilkS")
        (effects (font (size 0.7 0.7) (thickness 0.127)))
    )
    (fp_text value "R_100k_0402" (at 0 1.17 -90) (layer "F.Fab")
        (effects (font (size 1 1) (thickness 0.15)))
    )
    (fp_text user "${REFERENCE}" (at 0 0 -90) (layer "F.Fab")
        (effects (font (size 0.25 0.25) (thickness 0.04)))
    )
    (fp_text user "License: Apache-2.0" (at -0.95 5.169 -90) (layer "F.Fab") hide
        (effects (font (size 0.7 0.7) (thickness 0.15)) (justify left bottom))
    )
    (fp_text user "Author: Antmicro" (at -0.95 4.169 -90) (layer "F.Fab") hide
        (effects (font (size 0.7 0.7) (thickness 0.15)) (justify left bottom))
    )
    (fp_rect (start -0.925 -0.47) (end 0.925 0.47)
      (stroke (width 0.05) (type default)) (fill none) (layer "F.CrtYd"))
    (fp_rect (start -0.5 -0.25) (end 0.5 0.25)
      (stroke (width 0.15) (type solid)) (fill none) (layer "F.Fab"))
    (pad "1" smd roundrect (at -0.48 0 270) (size 0.59 0.64) (layers "F.Cu" "F.Paste" "F.Mask") (roundrect_rratio 0.25)
      (net 11 "VCC5V0") (pintype "passive"))
    (pad "2" smd roundrect (at 0.48 0 270) (size 0.59 0.64) (layers "F.Cu" "F.Paste" "F.Mask") (roundrect_rratio 0.25)
      (net 422 "Net-(U12-FLAG3)") (pintype "passive"))
  )
)
